(kicad_pcb
	(version 20260206)
	(generator "pcbnew")
	(generator_version "10.0")
	(general
		(thickness 1.6)
		(legacy_teardrops no)
	)
	(paper "A4")
	(title_block
		(title "04192023_DAF0TMB3IC0_F0TG_MB_C_brd_V02_OCP.brd")
		(comment 1 "Grand Teton / footprints 6007-6013 of 8354")
	)
	(layers
		(0 "F.Cu" signal "TOP")
		(4 "In1.Cu" signal "GND")
		(6 "In2.Cu" signal "IN1")
		(8 "In3.Cu" signal "GND1")
		(10 "In4.Cu" signal "IN2")
		(12 "In5.Cu" signal "GND2")
		(14 "In6.Cu" signal "IN3")
		(16 "In7.Cu" signal "GND3")
		(18 "In8.Cu" signal "VCC")
		(20 "In9.Cu" signal "VCC1")
		(22 "In10.Cu" signal "GND4")
		(24 "In11.Cu" signal "IN4")
		(26 "In12.Cu" signal "GND5")
		(28 "In13.Cu" signal "IN5")
		(30 "In14.Cu" signal "GND6")
		(32 "In15.Cu" signal "IN6")
		(34 "In16.Cu" signal "GND7")
		(2 "B.Cu" signal "BOTTOM")
		(9 "F.Adhes" user "F.Adhesive")
		(11 "B.Adhes" user "B.Adhesive")
		(13 "F.Paste" user "Package Geometry/Pastemask Top")
		(15 "B.Paste" user "Package Geometry/Pastemask Bottom")
		(5 "F.SilkS" user "Ref Des/Silkscreen Top")
		(7 "B.SilkS" user "Ref Des/Silkscreen Bottom")
		(1 "F.Mask" user "Board Geometry/Soldermask Top")
		(3 "B.Mask" user "Board Geometry/Soldermask Bottom")
		(17 "Dwgs.User" user "User.Drawings")
		(19 "Cmts.User" user "User.Comments")
		(21 "Eco1.User" user "User.Eco1")
		(23 "Eco2.User" user "User.Eco2")
		(25 "Edge.Cuts" user "Board Geometry/Outline")
		(27 "Margin" user)
		(31 "F.CrtYd" user "Package Geometry/Place Bound Top")
		(29 "B.CrtYd" user "Package Geometry/Place Bound Bottom")
		(35 "F.Fab" user "Ref Des/Assembly Top")
		(33 "B.Fab" user "Ref Des/Assembly Bottom")
	)
	(footprint ""
		(layer "B.Cu")
		(at 98.51009 -248.479564 180)
		(property "Reference" "C2310"
			(at 0 0 0)
			(layer "B.SilkS")
			(hide yes)
			(effects
				(font
					(size 1.27 1.27)
				)
				(justify mirror)
			)
		)
		(property "Value" ""
			(at 0 0 0)
			(layer "B.Fab")
			(effects
				(font
					(size 1.27 1.27)
				)
				(justify mirror)
			)
		)
		(duplicate_pad_numbers_are_jumpers no)
		(fp_line
			(start 0.7874 0.4064)
			(end 0.7874 -0.4064)
			(stroke
				(width 0.1524)
				(type default)
			)
			(layer "B.SilkS")
		)
		(fp_line
			(start 0.7874 -0.4064)
			(end -0.7874 -0.4064)
			(stroke
				(width 0.1524)
				(type default)
			)
			(layer "B.SilkS")
		)
		(fp_line
			(start -0.7874 0.4064)
			(end 0.7874 0.4064)
			(stroke
				(width 0.1524)
				(type default)
			)
			(layer "B.SilkS")
		)
		(fp_line
			(start -0.7874 -0.4064)
			(end -0.7874 0.4064)
			(stroke
				(width 0.1524)
				(type default)
			)
			(layer "B.SilkS")
		)
		(fp_line
			(start 0.67945 0.3048)
			(end 0.67945 -0.305054)
			(stroke
				(width 0.1)
				(type default)
			)
			(layer "B.Fab")
		)
		(fp_line
			(start 0.67945 -0.305054)
			(end 0.12065 -0.305054)
			(stroke
				(width 0.1)
				(type default)
			)
			(layer "B.Fab")
		)
		(fp_line
			(start 0.12065 0.3048)
			(end 0.67945 0.3048)
			(stroke
				(width 0.1)
				(type default)
			)
			(layer "B.Fab")
		)
		(fp_line
			(start 0.12065 0.2794)
			(end 0.12065 0.3048)
			(stroke
				(width 0.1)
				(type default)
			)
			(layer "B.Fab")
		)
		(fp_line
			(start 0.12065 -0.2794)
			(end -0.12065 -0.2794)
			(stroke
				(width 0.1)
				(type default)
			)
			(layer "B.Fab")
		)
		(fp_line
			(start 0.12065 -0.305054)
			(end 0.12065 -0.2794)
			(stroke
				(width 0.1)
				(type default)
			)
			(layer "B.Fab")
		)
		(fp_line
			(start -0.120396 0.3048)
			(end -0.120396 0.2794)
			(stroke
				(width 0.1)
				(type default)
			)
			(layer "B.Fab")
		)
		(fp_line
			(start -0.120396 0.2794)
			(end 0.12065 0.2794)
			(stroke
				(width 0.1)
				(type default)
			)
			(layer "B.Fab")
		)
		(fp_line
			(start -0.12065 -0.2794)
			(end -0.12065 -0.3048)
			(stroke
				(width 0.1)
				(type default)
			)
			(layer "B.Fab")
		)
		(fp_line
			(start -0.12065 -0.3048)
			(end -0.67945 -0.3048)
			(stroke
				(width 0.1)
				(type default)
			)
			(layer "B.Fab")
		)
		(fp_line
			(start -0.67945 0.3048)
			(end -0.120396 0.3048)
			(stroke
				(width 0.1)
				(type default)
			)
			(layer "B.Fab")
		)
		(fp_line
			(start -0.67945 -0.3048)
			(end -0.67945 0.3048)
			(stroke
				(width 0.1)
				(type default)
			)
			(layer "B.Fab")
		)
		(pad "1" smd circle
			(at 0.40005 0)
			(size 0 0)
			(layers "B.Cu" "B.Mask" "B.Paste")
			(net "PVDDCR_CPU0_P1")
		)
		(pad "2" smd circle
			(at -0.40005 0)
			(size 0 0)
			(layers "B.Cu" "B.Mask" "B.Paste")
			(net "GND")
		)
	)
	(footprint ""
		(layer "B.Cu")
		(at 52.363624 -408.517344 90)
		(property "Reference" "C6664"
			(at 0 0 90)
			(layer "B.SilkS")
			(hide yes)
			(effects
				(font
					(size 1.27 1.27)
				)
				(justify mirror)
			)
		)
		(property "Value" ""
			(at 0 0 90)
			(layer "B.Fab")
			(effects
				(font
					(size 1.27 1.27)
				)
				(justify mirror)
			)
		)
		(duplicate_pad_numbers_are_jumpers no)
		(fp_line
			(start 0.299974 -0.150114)
			(end -0.299974 -0.150114)
			(stroke
				(width 0.1)
				(type default)
			)
			(layer "B.Fab")
		)
		(fp_line
			(start -0.299974 -0.150114)
			(end -0.299974 0.150114)
			(stroke
				(width 0.1)
				(type default)
			)
			(layer "B.Fab")
		)
		(fp_line
			(start 0.299974 0.150114)
			(end 0.299974 -0.150114)
			(stroke
				(width 0.1)
				(type default)
			)
			(layer "B.Fab")
		)
		(fp_line
			(start -0.299974 0.150114)
			(end 0.299974 0.150114)
			(stroke
				(width 0.1)
				(type default)
			)
			(layer "B.Fab")
		)
		(pad "1" smd rect
			(at 0.2667 0 270)
			(size 0.3048 0.381)
			(layers "B.Cu" "B.Mask" "B.Paste")
			(net "P5E_CPU1_P1_TX_BUF_C_DN<1>")
		)
		(pad "2" smd rect
			(at -0.2667 0 270)
			(size 0.3048 0.381)
			(layers "B.Cu" "B.Mask" "B.Paste")
			(net "P5E_CPU1_P1_TX_BUF_DN<1>")
		)
	)
	(footprint ""
		(layer "B.Cu")
		(at 191.897 -100.294948 -90)
		(property "Reference" "R268"
			(at 0 0 90)
			(layer "B.SilkS")
			(hide yes)
			(effects
				(font
					(size 1.27 1.27)
				)
				(justify mirror)
			)
		)
		(property "Value" ""
			(at 0 0 90)
			(layer "B.Fab")
			(effects
				(font
					(size 1.27 1.27)
				)
				(justify mirror)
			)
		)
		(duplicate_pad_numbers_are_jumpers no)
		(fp_line
			(start -0.7874 0.4064)
			(end 0.7874 0.4064)
			(stroke
				(width 0.1524)
				(type default)
			)
			(layer "B.SilkS")
		)
		(fp_line
			(start 0.7874 0.4064)
			(end 0.7874 -0.4064)
			(stroke
				(width 0.1524)
				(type default)
			)
			(layer "B.SilkS")
		)
		(fp_line
			(start -0.7874 -0.4064)
			(end -0.7874 0.4064)
			(stroke
				(width 0.1524)
				(type default)
			)
			(layer "B.SilkS")
		)
		(fp_line
			(start 0.7874 -0.4064)
			(end -0.7874 -0.4064)
			(stroke
				(width 0.1524)
				(type default)
			)
			(layer "B.SilkS")
		)
		(fp_line
			(start -0.67945 0.3048)
			(end -0.120396 0.3048)
			(stroke
				(width 0.1)
				(type default)
			)
			(layer "B.Fab")
		)
		(fp_line
			(start -0.120396 0.3048)
			(end -0.120396 0.2794)
			(stroke
				(width 0.1)
				(type default)
			)
			(layer "B.Fab")
		)
		(fp_line
			(start 0.12065 0.3048)
			(end 0.67945 0.3048)
			(stroke
				(width 0.1)
				(type default)
			)
			(layer "B.Fab")
		)
		(fp_line
			(start 0.67945 0.3048)
			(end 0.67945 -0.305054)
			(stroke
				(width 0.1)
				(type default)
			)
			(layer "B.Fab")
		)
		(fp_line
			(start -0.120396 0.2794)
			(end 0.12065 0.2794)
			(stroke
				(width 0.1)
				(type default)
			)
			(layer "B.Fab")
		)
		(fp_line
			(start 0.12065 0.2794)
			(end 0.12065 0.3048)
			(stroke
				(width 0.1)
				(type default)
			)
			(layer "B.Fab")
		)
		(fp_line
			(start -0.12065 -0.2794)
			(end -0.12065 -0.3048)
			(stroke
				(width 0.1)
				(type default)
			)
			(layer "B.Fab")
		)
		(fp_line
			(start 0.12065 -0.2794)
			(end -0.12065 -0.2794)
			(stroke
				(width 0.1)
				(type default)
			)
			(layer "B.Fab")
		)
		(fp_line
			(start -0.67945 -0.3048)
			(end -0.67945 0.3048)
			(stroke
				(width 0.1)
				(type default)
			)
			(layer "B.Fab")
		)
		(fp_line
			(start -0.12065 -0.3048)
			(end -0.67945 -0.3048)
			(stroke
				(width 0.1)
				(type default)
			)
			(layer "B.Fab")
		)
		(fp_line
			(start 0.12065 -0.305054)
			(end 0.12065 -0.2794)
			(stroke
				(width 0.1)
				(type default)
			)
			(layer "B.Fab")
		)
		(fp_line
			(start 0.67945 -0.305054)
			(end 0.12065 -0.305054)
			(stroke
				(width 0.1)
				(type default)
			)
			(layer "B.Fab")
		)
		(pad "1" smd circle
			(at 0.40005 0 90)
			(size 0 0)
			(layers "B.Cu" "B.Mask" "B.Paste")
			(net "CPU1_SP5R3")
		)
		(pad "2" smd circle
			(at -0.40005 0 90)
			(size 0 0)
			(layers "B.Cu" "B.Mask" "B.Paste")
			(net "FM_CPU1_SP5R3")
		)
	)
	(footprint ""
		(layer "B.Cu")
		(at 114.01806 -28.449778 -90)
		(property "Reference" "C6107"
			(at 0 0 90)
			(layer "B.SilkS")
			(hide yes)
			(effects
				(font
					(size 1.27 1.27)
				)
				(justify mirror)
			)
		)
		(property "Value" ""
			(at 0 0 90)
			(layer "B.Fab")
			(effects
				(font
					(size 1.27 1.27)
				)
				(justify mirror)
			)
		)
		(duplicate_pad_numbers_are_jumpers no)
		(fp_line
			(start -0.7874 0.4064)
			(end 0.7874 0.4064)
			(stroke
				(width 0.1524)
				(type default)
			)
			(layer "B.SilkS")
		)
		(fp_line
			(start 0.7874 0.4064)
			(end 0.7874 -0.4064)
			(stroke
				(width 0.1524)
				(type default)
			)
			(layer "B.SilkS")
		)
		(fp_line
			(start -0.7874 -0.4064)
			(end -0.7874 0.4064)
			(stroke
				(width 0.1524)
				(type default)
			)
			(layer "B.SilkS")
		)
		(fp_line
			(start 0.7874 -0.4064)
			(end -0.7874 -0.4064)
			(stroke
				(width 0.1524)
				(type default)
			)
			(layer "B.SilkS")
		)
		(fp_line
			(start -0.67945 0.3048)
			(end -0.120396 0.3048)
			(stroke
				(width 0.1)
				(type default)
			)
			(layer "B.Fab")
		)
		(fp_line
			(start -0.120396 0.3048)
			(end -0.120396 0.2794)
			(stroke
				(width 0.1)
				(type default)
			)
			(layer "B.Fab")
		)
		(fp_line
			(start 0.12065 0.3048)
			(end 0.67945 0.3048)
			(stroke
				(width 0.1)
				(type default)
			)
			(layer "B.Fab")
		)
		(fp_line
			(start 0.67945 0.3048)
			(end 0.67945 -0.305054)
			(stroke
				(width 0.1)
				(type default)
			)
			(layer "B.Fab")
		)
		(fp_line
			(start -0.120396 0.2794)
			(end 0.12065 0.2794)
			(stroke
				(width 0.1)
				(type default)
			)
			(layer "B.Fab")
		)
		(fp_line
			(start 0.12065 0.2794)
			(end 0.12065 0.3048)
			(stroke
				(width 0.1)
				(type default)
			)
			(layer "B.Fab")
		)
		(fp_line
			(start -0.12065 -0.2794)
			(end -0.12065 -0.3048)
			(stroke
				(width 0.1)
				(type default)
			)
			(layer "B.Fab")
		)
		(fp_line
			(start 0.12065 -0.2794)
			(end -0.12065 -0.2794)
			(stroke
				(width 0.1)
				(type default)
			)
			(layer "B.Fab")
		)
		(fp_line
			(start -0.67945 -0.3048)
			(end -0.67945 0.3048)
			(stroke
				(width 0.1)
				(type default)
			)
			(layer "B.Fab")
		)
		(fp_line
			(start -0.12065 -0.3048)
			(end -0.67945 -0.3048)
			(stroke
				(width 0.1)
				(type default)
			)
			(layer "B.Fab")
		)
		(fp_line
			(start 0.12065 -0.305054)
			(end 0.12065 -0.2794)
			(stroke
				(width 0.1)
				(type default)
			)
			(layer "B.Fab")
		)
		(fp_line
			(start 0.67945 -0.305054)
			(end 0.12065 -0.305054)
			(stroke
				(width 0.1)
				(type default)
			)
			(layer "B.Fab")
		)
		(pad "1" smd circle
			(at 0.40005 0 90)
			(size 0 0)
			(layers "B.Cu" "B.Mask" "B.Paste")
			(net "P1V2_CPU0_USB2_DVDD12")
		)
		(pad "2" smd circle
			(at -0.40005 0 90)
			(size 0 0)
			(layers "B.Cu" "B.Mask" "B.Paste")
			(net "GND")
		)
	)
	(footprint ""
		(layer "B.Cu")
		(at 95.964248 -182.555134 -90)
		(property "Reference" "PC298_3"
			(at 0 0 90)
			(layer "B.SilkS")
			(hide yes)
			(effects
				(font
					(size 1.27 1.27)
				)
				(justify mirror)
			)
		)
		(property "Value" ""
			(at 0 0 90)
			(layer "B.Fab")
			(effects
				(font
					(size 1.27 1.27)
				)
				(justify mirror)
			)
		)
		(duplicate_pad_numbers_are_jumpers no)
		(fp_line
			(start -1.524 0.762)
			(end 1.524 0.762)
			(stroke
				(width 0.1524)
				(type default)
			)
			(layer "B.SilkS")
		)
		(fp_line
			(start 1.524 0.762)
			(end 1.524 -0.762)
			(stroke
				(width 0.1524)
				(type default)
			)
			(layer "B.SilkS")
		)
		(fp_line
			(start -1.524 -0.762)
			(end -1.524 0.762)
			(stroke
				(width 0.1524)
				(type default)
			)
			(layer "B.SilkS")
		)
		(fp_line
			(start 1.524 -0.762)
			(end -1.524 -0.762)
			(stroke
				(width 0.1524)
				(type default)
			)
			(layer "B.SilkS")
		)
		(fp_line
			(start -1.1049 0.724916)
			(end -1.1049 -0.724916)
			(stroke
				(width 0.1)
				(type default)
			)
			(layer "B.Fab")
		)
		(fp_line
			(start 1.1049 0.724916)
			(end -1.1049 0.724916)
			(stroke
				(width 0.1)
				(type default)
			)
			(layer "B.Fab")
		)
		(fp_line
			(start -1.1049 -0.724916)
			(end 1.1049 -0.724916)
			(stroke
				(width 0.1)
				(type default)
			)
			(layer "B.Fab")
		)
		(fp_line
			(start 1.1049 -0.724916)
			(end 1.1049 0.724916)
			(stroke
				(width 0.1)
				(type default)
			)
			(layer "B.Fab")
		)
		(pad "1" smd rect
			(at 0.889 0 270)
			(size 1.016 1.27)
			(layers "B.Cu" "B.Mask" "B.Paste")
			(net "SW_P12V_AUX_PVDDCR_CPU0_P1_FLT")
		)
		(pad "2" smd rect
			(at -0.889 0 270)
			(size 1.016 1.27)
			(layers "B.Cu" "B.Mask" "B.Paste")
			(net "GND")
		)
	)
	(footprint ""
		(layer "B.Cu")
		(at 292.28034 -192.660016)
		(property "Reference" "C147"
			(at 0 0 0)
			(layer "B.SilkS")
			(hide yes)
			(effects
				(font
					(size 1.27 1.27)
				)
				(justify mirror)
			)
		)
		(property "Value" ""
			(at 0 0 0)
			(layer "B.Fab")
			(effects
				(font
					(size 1.27 1.27)
				)
				(justify mirror)
			)
		)
		(duplicate_pad_numbers_are_jumpers no)
		(fp_line
			(start -1.524 -0.762)
			(end -1.524 0.762)
			(stroke
				(width 0.1524)
				(type default)
			)
			(layer "B.SilkS")
		)
		(fp_line
			(start -1.524 0.762)
			(end 1.524 0.762)
			(stroke
				(width 0.1524)
				(type default)
			)
			(layer "B.SilkS")
		)
		(fp_line
			(start 1.524 -0.762)
			(end -1.524 -0.762)
			(stroke
				(width 0.1524)
				(type default)
			)
			(layer "B.SilkS")
		)
		(fp_line
			(start 1.524 0.762)
			(end 1.524 -0.762)
			(stroke
				(width 0.1524)
				(type default)
			)
			(layer "B.SilkS")
		)
		(fp_line
			(start -1.1049 -0.724916)
			(end 1.1049 -0.724916)
			(stroke
				(width 0.1)
				(type default)
			)
			(layer "B.Fab")
		)
		(fp_line
			(start -1.1049 0.724916)
			(end -1.1049 -0.724916)
			(stroke
				(width 0.1)
				(type default)
			)
			(layer "B.Fab")
		)
		(fp_line
			(start 1.1049 -0.724916)
			(end 1.1049 0.724916)
			(stroke
				(width 0.1)
				(type default)
			)
			(layer "B.Fab")
		)
		(fp_line
			(start 1.1049 0.724916)
			(end -1.1049 0.724916)
			(stroke
				(width 0.1)
				(type default)
			)
			(layer "B.Fab")
		)
		(pad "1" smd rect
			(at 0.889 0)
			(size 1.016 1.27)
			(layers "B.Cu" "B.Mask" "B.Paste")
			(net "P12V_MEM_CPU0")
		)
		(pad "2" smd rect
			(at -0.889 0)
			(size 1.016 1.27)
			(layers "B.Cu" "B.Mask" "B.Paste")
			(net "GND")
		)
	)
	(footprint ""
		(layer "B.Cu")
		(at 70.500494 -328.24547 -90)
		(property "Reference" "PC387"
			(at 10.257536 -0.312166 270)
			(unlocked yes)
			(layer "B.SilkS")
			(effects
				(font
					(size 0.7874 0.5842)
					(thickness 0.1524)
				)
				(justify left mirror)
			)
		)
		(property "Value" ""
			(at 0 0 90)
			(layer "B.Fab")
			(effects
				(font
					(size 1.27 1.27)
				)
				(justify mirror)
			)
		)
		(duplicate_pad_numbers_are_jumpers no)
		(fp_line
			(start -4.533392 2.249932)
			(end 4.533392 2.249932)
			(stroke
				(width 0.1524)
				(type default)
			)
			(layer "B.SilkS")
		)
		(fp_line
			(start 4.533392 2.249932)
			(end 4.533392 -2.249932)
			(stroke
				(width 0.1524)
				(type default)
			)
			(layer "B.SilkS")
		)
		(fp_line
			(start -4.533392 -2.249932)
			(end -4.533392 2.249932)
			(stroke
				(width 0.1524)
				(type default)
			)
			(layer "B.SilkS")
		)
		(fp_line
			(start 4.533392 -2.249932)
			(end -4.533392 -2.249932)
			(stroke
				(width 0.1524)
				(type default)
			)
			(layer "B.SilkS")
		)
		(fp_rect
			(start 5.39242 2.326132)
			(end 4.533392 -2.326132)
			(stroke
				(width 0)
				(type default)
			)
			(fill yes)
			(layer "B.SilkS")
		)
		(fp_line
			(start -3.750056 2.249932)
			(end 3.750056 2.249932)
			(stroke
				(width 0.1)
				(type default)
			)
			(layer "B.Fab")
		)
		(fp_line
			(start 3.750056 2.249932)
			(end 3.750056 -2.249932)
			(stroke
				(width 0.1)
				(type default)
			)
			(layer "B.Fab")
		)
		(fp_line
			(start -3.750056 -2.249932)
			(end -3.750056 2.249932)
			(stroke
				(width 0.1)
				(type default)
			)
			(layer "B.Fab")
		)
		(fp_line
			(start 3.750056 -2.249932)
			(end -3.750056 -2.249932)
			(stroke
				(width 0.1)
				(type default)
			)
			(layer "B.Fab")
		)
		(fp_text user "-"
			(at -4.489196 2.477516 270)
			(unlocked yes)
			(layer "B.SilkS")
			(effects
				(font
					(size 1.905 1.4224)
					(thickness 0.1524)
				)
				(justify left mirror)
			)
		)
		(fp_text user "+"
			(at 6.322314 0.786384 180)
			(unlocked yes)
			(layer "B.SilkS")
			(effects
				(font
					(size 1.905 1.4224)
					(thickness 0.1524)
				)
				(justify left mirror)
			)
		)
		(fp_text user "+"
			(at 6.322314 0.786384 180)
			(unlocked yes)
			(layer "B.Fab")
			(effects
				(font
					(size 1.905 1.4224)
					(thickness 0.1524)
				)
				(justify left mirror)
			)
		)
		(fp_text user "-"
			(at -4.8514 -0.14605 270)
			(unlocked yes)
			(layer "B.Fab")
			(effects
				(font
					(size 1.905 1.4224)
					(thickness 0.1524)
				)
				(justify left mirror)
			)
		)
		(pad "1" smd rect
			(at 3.199892 0 90)
			(size 2.413 2.8194)
			(layers "B.Cu" "B.Mask" "B.Paste")
			(net "PVDDCR_CPU1_P1")
		)
		(pad "2" smd rect
			(at -3.199892 0 90)
			(size 2.413 2.8194)
			(layers "B.Cu" "B.Mask" "B.Paste")
			(net "GND")
		)
	)
)
